# T6G (Grand Teton) — schematic netlist excerpt (pin names and nets, part order shuffled) for the footprints in the layout excerpt that follows; sources: Cadence DE-HDL packaged netlist, KiCad conversion of 04192023_DAF0TMB3IC0_F0TG_MB_C_brd_V02_OCP.brd

C989  Q_CAP  0.1UF 10V 10% X7S  pkg C0201  page 300 : A = P1V8_CPU0_RT_1D ; B = GND
R1176  Q_RES  10K 1% CHIP  pkg 0402LF  page 142 : A = P3V3_AUX ; B = FM_OCP_V3_2_AUX_PWR_R_EN
R6332  Q_RES  12K 1% CHIP  pkg 0402LF  page 178 : A = USB_HUB2_TI_USB_R1_MRP_RBIAS ; B = GND

(kicad_pcb
	(version 20260206)
	(generator "pcbnew")
	(generator_version "10.0")
	(general
		(thickness 1.6)
		(legacy_teardrops no)
	)
	(paper "A4")
	(title_block
		(title "04192023_DAF0TMB3IC0_F0TG_MB_C_brd_V02_OCP.brd")
		(comment 1 "Grand Teton / footprints 4349-4351 of 8354")
	)
	(layers
		(0 "F.Cu" signal "TOP")
		(4 "In1.Cu" signal "GND")
		(6 "In2.Cu" signal "IN1")
		(8 "In3.Cu" signal "GND1")
		(10 "In4.Cu" signal "IN2")
		(12 "In5.Cu" signal "GND2")
		(14 "In6.Cu" signal "IN3")
		(16 "In7.Cu" signal "GND3")
		(18 "In8.Cu" signal "VCC")
		(20 "In9.Cu" signal "VCC1")
		(22 "In10.Cu" signal "GND4")
		(24 "In11.Cu" signal "IN4")
		(26 "In12.Cu" signal "GND5")
		(28 "In13.Cu" signal "IN5")
		(30 "In14.Cu" signal "GND6")
		(32 "In15.Cu" signal "IN6")
		(34 "In16.Cu" signal "GND7")
		(2 "B.Cu" signal "BOTTOM")
		(9 "F.Adhes" user "F.Adhesive")
		(11 "B.Adhes" user "B.Adhesive")
		(13 "F.Paste" user "Package Geometry/Pastemask Top")
		(15 "B.Paste" user "Package Geometry/Pastemask Bottom")
		(5 "F.SilkS" user "Ref Des/Silkscreen Top")
		(7 "B.SilkS" user "Ref Des/Silkscreen Bottom")
		(1 "F.Mask" user "Board Geometry/Soldermask Top")
		(3 "B.Mask" user "Board Geometry/Soldermask Bottom")
		(17 "Dwgs.User" user "User.Drawings")
		(19 "Cmts.User" user "User.Comments")
		(21 "Eco1.User" user "User.Eco1")
		(23 "Eco2.User" user "User.Eco2")
		(25 "Edge.Cuts" user "Board Geometry/Outline")
		(27 "Margin" user)
		(31 "F.CrtYd" user "Package Geometry/Place Bound Top")
		(29 "B.CrtYd" user "Package Geometry/Place Bound Bottom")
		(35 "F.Fab" user "Ref Des/Assembly Top")
		(33 "B.Fab" user "Ref Des/Assembly Bottom")
	)
	(footprint ""
		(layer "F.Cu")
		(at 110.15599 -23.534878 -90)
		(property "Reference" "R6332"
			(at 0 0 270)
			(layer "F.SilkS")
			(hide yes)
			(effects
				(font
					(size 1.27 1.27)
				)
			)
		)
		(property "Value" ""
			(at 0 0 270)
			(layer "F.Fab")
			(effects
				(font
					(size 1.27 1.27)
				)
			)
		)
		(duplicate_pad_numbers_are_jumpers no)
		(fp_line
			(start -0.7874 0.4064)
			(end -0.7874 -0.4064)
			(stroke
				(width 0.1524)
				(type default)
			)
			(layer "F.SilkS")
		)
		(fp_line
			(start 0.7874 0.4064)
			(end -0.7874 0.4064)
			(stroke
				(width 0.1524)
				(type default)
			)
			(layer "F.SilkS")
		)
		(fp_line
			(start -0.7874 -0.4064)
			(end 0.7874 -0.4064)
			(stroke
				(width 0.1524)
				(type default)
			)
			(layer "F.SilkS")
		)
		(fp_line
			(start 0.7874 -0.4064)
			(end 0.7874 0.4064)
			(stroke
				(width 0.1524)
				(type default)
			)
			(layer "F.SilkS")
		)
		(fp_line
			(start -0.67945 0.3048)
			(end -0.67945 -0.305054)
			(stroke
				(width 0.1)
				(type default)
			)
			(layer "F.Fab")
		)
		(fp_line
			(start -0.12065 0.3048)
			(end -0.67945 0.3048)
			(stroke
				(width 0.1)
				(type default)
			)
			(layer "F.Fab")
		)
		(fp_line
			(start 0.120396 0.3048)
			(end 0.120396 0.2794)
			(stroke
				(width 0.1)
				(type default)
			)
			(layer "F.Fab")
		)
		(fp_line
			(start 0.67945 0.3048)
			(end 0.120396 0.3048)
			(stroke
				(width 0.1)
				(type default)
			)
			(layer "F.Fab")
		)
		(fp_line
			(start -0.12065 0.2794)
			(end -0.12065 0.3048)
			(stroke
				(width 0.1)
				(type default)
			)
			(layer "F.Fab")
		)
		(fp_line
			(start 0.120396 0.2794)
			(end -0.12065 0.2794)
			(stroke
				(width 0.1)
				(type default)
			)
			(layer "F.Fab")
		)
		(fp_line
			(start -0.12065 -0.2794)
			(end 0.12065 -0.2794)
			(stroke
				(width 0.1)
				(type default)
			)
			(layer "F.Fab")
		)
		(fp_line
			(start 0.12065 -0.2794)
			(end 0.12065 -0.3048)
			(stroke
				(width 0.1)
				(type default)
			)
			(layer "F.Fab")
		)
		(fp_line
			(start 0.12065 -0.3048)
			(end 0.67945 -0.3048)
			(stroke
				(width 0.1)
				(type default)
			)
			(layer "F.Fab")
		)
		(fp_line
			(start 0.67945 -0.3048)
			(end 0.67945 0.3048)
			(stroke
				(width 0.1)
				(type default)
			)
			(layer "F.Fab")
		)
		(fp_line
			(start -0.67945 -0.305054)
			(end -0.12065 -0.305054)
			(stroke
				(width 0.1)
				(type default)
			)
			(layer "F.Fab")
		)
		(fp_line
			(start -0.12065 -0.305054)
			(end -0.12065 -0.2794)
			(stroke
				(width 0.1)
				(type default)
			)
			(layer "F.Fab")
		)
		(pad "1" smd circle
			(at -0.40005 0 270)
			(size 0 0)
			(layers "F.Cu" "F.Mask" "F.Paste")
			(net "USB_HUB2_TI_USB_R1_MRP_RBIAS")
		)
		(pad "2" smd circle
			(at 0.40005 0 270)
			(size 0 0)
			(layers "F.Cu" "F.Mask" "F.Paste")
			(net "GND")
		)
	)
	(footprint ""
		(layer "F.Cu")
		(at 66.929 -56.261)
		(property "Reference" "R1176"
			(at 0 0 0)
			(layer "F.SilkS")
			(hide yes)
			(effects
				(font
					(size 1.27 1.27)
				)
			)
		)
		(property "Value" ""
			(at 0 0 0)
			(layer "F.Fab")
			(effects
				(font
					(size 1.27 1.27)
				)
			)
		)
		(duplicate_pad_numbers_are_jumpers no)
		(fp_line
			(start -0.7874 -0.4064)
			(end 0.7874 -0.4064)
			(stroke
				(width 0.1524)
				(type default)
			)
			(layer "F.SilkS")
		)
		(fp_line
			(start -0.7874 0.4064)
			(end -0.7874 -0.4064)
			(stroke
				(width 0.1524)
				(type default)
			)
			(layer "F.SilkS")
		)
		(fp_line
			(start 0.7874 -0.4064)
			(end 0.7874 0.4064)
			(stroke
				(width 0.1524)
				(type default)
			)
			(layer "F.SilkS")
		)
		(fp_line
			(start 0.7874 0.4064)
			(end -0.7874 0.4064)
			(stroke
				(width 0.1524)
				(type default)
			)
			(layer "F.SilkS")
		)
		(fp_line
			(start -0.67945 -0.305054)
			(end -0.12065 -0.305054)
			(stroke
				(width 0.1)
				(type default)
			)
			(layer "F.Fab")
		)
		(fp_line
			(start -0.67945 0.3048)
			(end -0.67945 -0.305054)
			(stroke
				(width 0.1)
				(type default)
			)
			(layer "F.Fab")
		)
		(fp_line
			(start -0.12065 -0.305054)
			(end -0.12065 -0.2794)
			(stroke
				(width 0.1)
				(type default)
			)
			(layer "F.Fab")
		)
		(fp_line
			(start -0.12065 -0.2794)
			(end 0.12065 -0.2794)
			(stroke
				(width 0.1)
				(type default)
			)
			(layer "F.Fab")
		)
		(fp_line
			(start -0.12065 0.2794)
			(end -0.12065 0.3048)
			(stroke
				(width 0.1)
				(type default)
			)
			(layer "F.Fab")
		)
		(fp_line
			(start -0.12065 0.3048)
			(end -0.67945 0.3048)
			(stroke
				(width 0.1)
				(type default)
			)
			(layer "F.Fab")
		)
		(fp_line
			(start 0.120396 0.2794)
			(end -0.12065 0.2794)
			(stroke
				(width 0.1)
				(type default)
			)
			(layer "F.Fab")
		)
		(fp_line
			(start 0.120396 0.3048)
			(end 0.120396 0.2794)
			(stroke
				(width 0.1)
				(type default)
			)
			(layer "F.Fab")
		)
		(fp_line
			(start 0.12065 -0.3048)
			(end 0.67945 -0.3048)
			(stroke
				(width 0.1)
				(type default)
			)
			(layer "F.Fab")
		)
		(fp_line
			(start 0.12065 -0.2794)
			(end 0.12065 -0.3048)
			(stroke
				(width 0.1)
				(type default)
			)
			(layer "F.Fab")
		)
		(fp_line
			(start 0.67945 -0.3048)
			(end 0.67945 0.3048)
			(stroke
				(width 0.1)
				(type default)
			)
			(layer "F.Fab")
		)
		(fp_line
			(start 0.67945 0.3048)
			(end 0.120396 0.3048)
			(stroke
				(width 0.1)
				(type default)
			)
			(layer "F.Fab")
		)
		(pad "1" smd circle
			(at -0.40005 0)
			(size 0 0)
			(layers "F.Cu" "F.Mask" "F.Paste")
			(net "P3V3_AUX")
		)
		(pad "2" smd circle
			(at 0.40005 0)
			(size 0 0)
			(layers "F.Cu" "F.Mask" "F.Paste")
			(net "FM_OCP_V3_2_AUX_PWR_R_EN")
		)
	)
	(footprint ""
		(layer "F.Cu")
		(at 423.473372 -424.217846)
		(property "Reference" "C989"
			(at 0 0 0)
			(layer "F.SilkS")
			(hide yes)
			(effects
				(font
					(size 1.27 1.27)
				)
			)
		)
		(property "Value" ""
			(at 0 0 0)
			(layer "F.Fab")
			(effects
				(font
					(size 1.27 1.27)
				)
			)
		)
		(duplicate_pad_numbers_are_jumpers no)
		(fp_line
			(start -0.299974 -0.150114)
			(end 0.299974 -0.150114)
			(stroke
				(width 0.1)
				(type default)
			)
			(layer "F.Fab")
		)
		(fp_line
			(start -0.299974 0.150114)
			(end -0.299974 -0.150114)
			(stroke
				(width 0.1)
				(type default)
			)
			(layer "F.Fab")
		)
		(fp_line
			(start 0.299974 -0.150114)
			(end 0.299974 0.150114)
			(stroke
				(width 0.1)
				(type default)
			)
			(layer "F.Fab")
		)
		(fp_line
			(start 0.299974 0.150114)
			(end -0.299974 0.150114)
			(stroke
				(width 0.1)
				(type default)
			)
			(layer "F.Fab")
		)
		(pad "1" smd rect
			(at -0.2667 0)
			(size 0.3048 0.381)
			(layers "F.Cu" "F.Mask" "F.Paste")
			(net "P1V8_CPU0_RT_1D")
		)
		(pad "2" smd rect
			(at 0.2667 0)
			(size 0.3048 0.381)
			(layers "F.Cu" "F.Mask" "F.Paste")
			(net "GND")
		)
	)
)
